# S9S_MB_2U (Grand Teton) — schematic netlist excerpt (pin names and nets, part order shuffled) for the footprints in the layout excerpt that follows; sources: Cadence DE-HDL packaged netlist, KiCad conversion of 03242023_DA0F0TMBIJ0_F0T_Motherboard_J_brd_V01_OCP.brd

R1296  Q_RES  0 5% CHIP  pkg 0402LF  page 154 : A = NCSI_BMC_TXD1_R ; B = RMII_BMC_OCP_TXD_1
C699  Q_CAP_DIFFBUS  DIFF BUS_0.22UF 6.3V 20% X6S  pkg C0201  page 177 : \1\ = P5E_CPU1_PE4_TX_C_DP<5> ; \2\ = P5E_CPU1_PE4_TX_DP<5>
R4613  Q_RES  0 5% EMPTY  pkg 0402LF  page 158 : A = OCP_V3_1_P3V3_PWRGD ; B = HP_OCP_V3_1_RST_R

(kicad_pcb
	(version 20260206)
	(generator "pcbnew")
	(generator_version "10.0")
	(general
		(thickness 1.6)
		(legacy_teardrops no)
	)
	(paper "A4")
	(title_block
		(title "03242023_DA0F0TMBIJ0_F0T_Motherboard_J_brd_V01_OCP.brd")
		(comment 1 "Grand Teton / footprints 221-223 of 6105")
	)
	(layers
		(0 "F.Cu" signal "TOP")
		(4 "In1.Cu" signal "GND")
		(6 "In2.Cu" signal "IN1")
		(8 "In3.Cu" signal "GND1")
		(10 "In4.Cu" signal "IN2")
		(12 "In5.Cu" signal "GND2")
		(14 "In6.Cu" signal "IN3")
		(16 "In7.Cu" signal "GND3")
		(18 "In8.Cu" signal "VCC")
		(20 "In9.Cu" signal "VCC1")
		(22 "In10.Cu" signal "GND4")
		(24 "In11.Cu" signal "IN4")
		(26 "In12.Cu" signal "GND5")
		(28 "In13.Cu" signal "IN5")
		(30 "In14.Cu" signal "GND6")
		(32 "In15.Cu" signal "IN6")
		(34 "In16.Cu" signal "GND7")
		(2 "B.Cu" signal "BOTTOM")
		(9 "F.Adhes" user "F.Adhesive")
		(11 "B.Adhes" user "B.Adhesive")
		(13 "F.Paste" user "Package Geometry/Pastemask Top")
		(15 "B.Paste" user "Package Geometry/Pastemask Bottom")
		(5 "F.SilkS" user "Ref Des/Silkscreen Top")
		(7 "B.SilkS" user "Ref Des/Silkscreen Bottom")
		(1 "F.Mask" user "Board Geometry/Soldermask Top")
		(3 "B.Mask" user "Board Geometry/Soldermask Bottom")
		(17 "Dwgs.User" user "User.Drawings")
		(19 "Cmts.User" user "User.Comments")
		(21 "Eco1.User" user "User.Eco1")
		(23 "Eco2.User" user "User.Eco2")
		(25 "Edge.Cuts" user "Board Geometry/Outline")
		(27 "Margin" user)
		(31 "F.CrtYd" user "Package Geometry/Place Bound Top")
		(29 "B.CrtYd" user "Package Geometry/Place Bound Bottom")
		(35 "F.Fab" user "Ref Des/Assembly Top")
		(33 "B.Fab" user "Ref Des/Assembly Bottom")
	)
	(footprint ""
		(layer "F.Cu")
		(at 389.636 -30.825948 180)
		(property "Reference" "R4613"
			(at 0 0 180)
			(layer "F.SilkS")
			(hide yes)
			(effects
				(font
					(size 1.27 1.27)
				)
			)
		)
		(property "Value" ""
			(at 0 0 180)
			(layer "F.Fab")
			(effects
				(font
					(size 1.27 1.27)
				)
			)
		)
		(duplicate_pad_numbers_are_jumpers no)
		(fp_line
			(start 0.7874 0.4064)
			(end -0.7874 0.4064)
			(stroke
				(width 0.1524)
				(type default)
			)
			(layer "F.SilkS")
		)
		(fp_line
			(start 0.7874 -0.4064)
			(end 0.7874 0.4064)
			(stroke
				(width 0.1524)
				(type default)
			)
			(layer "F.SilkS")
		)
		(fp_line
			(start -0.7874 0.4064)
			(end -0.7874 -0.4064)
			(stroke
				(width 0.1524)
				(type default)
			)
			(layer "F.SilkS")
		)
		(fp_line
			(start -0.7874 -0.4064)
			(end 0.7874 -0.4064)
			(stroke
				(width 0.1524)
				(type default)
			)
			(layer "F.SilkS")
		)
		(fp_line
			(start 0.67945 0.3048)
			(end 0.120396 0.3048)
			(stroke
				(width 0.1)
				(type default)
			)
			(layer "F.Fab")
		)
		(fp_line
			(start 0.67945 -0.3048)
			(end 0.67945 0.3048)
			(stroke
				(width 0.1)
				(type default)
			)
			(layer "F.Fab")
		)
		(fp_line
			(start 0.12065 -0.2794)
			(end 0.12065 -0.3048)
			(stroke
				(width 0.1)
				(type default)
			)
			(layer "F.Fab")
		)
		(fp_line
			(start 0.12065 -0.3048)
			(end 0.67945 -0.3048)
			(stroke
				(width 0.1)
				(type default)
			)
			(layer "F.Fab")
		)
		(fp_line
			(start 0.120396 0.3048)
			(end 0.120396 0.2794)
			(stroke
				(width 0.1)
				(type default)
			)
			(layer "F.Fab")
		)
		(fp_line
			(start 0.120396 0.2794)
			(end -0.12065 0.2794)
			(stroke
				(width 0.1)
				(type default)
			)
			(layer "F.Fab")
		)
		(fp_line
			(start -0.12065 0.3048)
			(end -0.67945 0.3048)
			(stroke
				(width 0.1)
				(type default)
			)
			(layer "F.Fab")
		)
		(fp_line
			(start -0.12065 0.2794)
			(end -0.12065 0.3048)
			(stroke
				(width 0.1)
				(type default)
			)
			(layer "F.Fab")
		)
		(fp_line
			(start -0.12065 -0.2794)
			(end 0.12065 -0.2794)
			(stroke
				(width 0.1)
				(type default)
			)
			(layer "F.Fab")
		)
		(fp_line
			(start -0.12065 -0.305054)
			(end -0.12065 -0.2794)
			(stroke
				(width 0.1)
				(type default)
			)
			(layer "F.Fab")
		)
		(fp_line
			(start -0.67945 0.3048)
			(end -0.67945 -0.305054)
			(stroke
				(width 0.1)
				(type default)
			)
			(layer "F.Fab")
		)
		(fp_line
			(start -0.67945 -0.305054)
			(end -0.12065 -0.305054)
			(stroke
				(width 0.1)
				(type default)
			)
			(layer "F.Fab")
		)
		(pad "1" smd circle
			(at -0.40005 0 180)
			(size 0 0)
			(layers "F.Cu" "F.Mask" "F.Paste")
			(net "OCP_V3_1_P3V3_PWRGD")
		)
		(pad "2" smd circle
			(at 0.40005 0 180)
			(size 0 0)
			(layers "F.Cu" "F.Mask" "F.Paste")
			(net "HP_OCP_V3_1_RST_R")
		)
	)
	(footprint ""
		(layer "F.Cu")
		(at 209.069432 -69.82079)
		(property "Reference" "R1296"
			(at 0 0 0)
			(layer "F.SilkS")
			(hide yes)
			(effects
				(font
					(size 1.27 1.27)
				)
			)
		)
		(property "Value" ""
			(at 0 0 0)
			(layer "F.Fab")
			(effects
				(font
					(size 1.27 1.27)
				)
			)
		)
		(duplicate_pad_numbers_are_jumpers no)
		(fp_line
			(start -0.7874 -0.4064)
			(end 0.7874 -0.4064)
			(stroke
				(width 0.1524)
				(type default)
			)
			(layer "F.SilkS")
		)
		(fp_line
			(start -0.7874 0.4064)
			(end -0.7874 -0.4064)
			(stroke
				(width 0.1524)
				(type default)
			)
			(layer "F.SilkS")
		)
		(fp_line
			(start 0.7874 -0.4064)
			(end 0.7874 0.4064)
			(stroke
				(width 0.1524)
				(type default)
			)
			(layer "F.SilkS")
		)
		(fp_line
			(start 0.7874 0.4064)
			(end -0.7874 0.4064)
			(stroke
				(width 0.1524)
				(type default)
			)
			(layer "F.SilkS")
		)
		(fp_line
			(start -0.67945 -0.305054)
			(end -0.12065 -0.305054)
			(stroke
				(width 0.1)
				(type default)
			)
			(layer "F.Fab")
		)
		(fp_line
			(start -0.67945 0.3048)
			(end -0.67945 -0.305054)
			(stroke
				(width 0.1)
				(type default)
			)
			(layer "F.Fab")
		)
		(fp_line
			(start -0.12065 -0.305054)
			(end -0.12065 -0.2794)
			(stroke
				(width 0.1)
				(type default)
			)
			(layer "F.Fab")
		)
		(fp_line
			(start -0.12065 -0.2794)
			(end 0.12065 -0.2794)
			(stroke
				(width 0.1)
				(type default)
			)
			(layer "F.Fab")
		)
		(fp_line
			(start -0.12065 0.2794)
			(end -0.12065 0.3048)
			(stroke
				(width 0.1)
				(type default)
			)
			(layer "F.Fab")
		)
		(fp_line
			(start -0.12065 0.3048)
			(end -0.67945 0.3048)
			(stroke
				(width 0.1)
				(type default)
			)
			(layer "F.Fab")
		)
		(fp_line
			(start 0.120396 0.2794)
			(end -0.12065 0.2794)
			(stroke
				(width 0.1)
				(type default)
			)
			(layer "F.Fab")
		)
		(fp_line
			(start 0.120396 0.3048)
			(end 0.120396 0.2794)
			(stroke
				(width 0.1)
				(type default)
			)
			(layer "F.Fab")
		)
		(fp_line
			(start 0.12065 -0.3048)
			(end 0.67945 -0.3048)
			(stroke
				(width 0.1)
				(type default)
			)
			(layer "F.Fab")
		)
		(fp_line
			(start 0.12065 -0.2794)
			(end 0.12065 -0.3048)
			(stroke
				(width 0.1)
				(type default)
			)
			(layer "F.Fab")
		)
		(fp_line
			(start 0.67945 -0.3048)
			(end 0.67945 0.3048)
			(stroke
				(width 0.1)
				(type default)
			)
			(layer "F.Fab")
		)
		(fp_line
			(start 0.67945 0.3048)
			(end 0.120396 0.3048)
			(stroke
				(width 0.1)
				(type default)
			)
			(layer "F.Fab")
		)
		(pad "1" smd circle
			(at -0.40005 0)
			(size 0 0)
			(layers "F.Cu" "F.Mask" "F.Paste")
			(net "NCSI_BMC_TXD1_R")
		)
		(pad "2" smd circle
			(at 0.40005 0)
			(size 0 0)
			(layers "F.Cu" "F.Mask" "F.Paste")
			(net "RMII_BMC_OCP_TXD_1")
		)
	)
	(footprint ""
		(layer "F.Cu")
		(at 65.531238 -408.517344 -90)
		(property "Reference" "C699"
			(at 0 0 270)
			(layer "F.SilkS")
			(hide yes)
			(effects
				(font
					(size 1.27 1.27)
				)
			)
		)
		(property "Value" ""
			(at 0 0 270)
			(layer "F.Fab")
			(effects
				(font
					(size 1.27 1.27)
				)
			)
		)
		(duplicate_pad_numbers_are_jumpers no)
		(fp_line
			(start -0.299974 0.150114)
			(end -0.299974 -0.150114)
			(stroke
				(width 0.1)
				(type default)
			)
			(layer "F.Fab")
		)
		(fp_line
			(start 0.299974 0.150114)
			(end -0.299974 0.150114)
			(stroke
				(width 0.1)
				(type default)
			)
			(layer "F.Fab")
		)
		(fp_line
			(start -0.299974 -0.150114)
			(end 0.299974 -0.150114)
			(stroke
				(width 0.1)
				(type default)
			)
			(layer "F.Fab")
		)
		(fp_line
			(start 0.299974 -0.150114)
			(end 0.299974 0.150114)
			(stroke
				(width 0.1)
				(type default)
			)
			(layer "F.Fab")
		)
		(pad "1" smd rect
			(at -0.2667 0 270)
			(size 0.3048 0.381)
			(layers "F.Cu" "F.Mask" "F.Paste")
			(net "P5E_CPU1_PE4_TX_C_DP<5>")
		)
		(pad "2" smd rect
			(at 0.2667 0 270)
			(size 0.3048 0.381)
			(layers "F.Cu" "F.Mask" "F.Paste")
			(net "P5E_CPU1_PE4_TX_DP<5>")
		)
	)
)
